(kicad_pcb
	(version 20260206)
	(generator "pcbnew")
	(generator_version "10.0")
	(general
		(thickness 1.6)
		(legacy_teardrops no)
	)
	(paper "A4")
	(title_block
		(title "9052_F0T_PDB_Converter_Brick_F_V03_1208_1600_OCP.brd")
		(comment 1 "Grand Teton / footprints 180-185 of 578")
	)
	(layers
		(0 "F.Cu" signal "TOP")
		(4 "In1.Cu" signal "GND")
		(6 "In2.Cu" signal "IN1")
		(8 "In3.Cu" signal "GND1")
		(10 "In4.Cu" signal "VCC")
		(12 "In5.Cu" signal "VCC1")
		(14 "In6.Cu" signal "GND2")
		(16 "In7.Cu" signal "IN2")
		(18 "In8.Cu" signal "GND3")
		(2 "B.Cu" signal "BOTTOM")
		(9 "F.Adhes" user "F.Adhesive")
		(11 "B.Adhes" user "B.Adhesive")
		(13 "F.Paste" user "Package Geometry/Pastemask Top")
		(15 "B.Paste" user "Package Geometry/Pastemask Bottom")
		(5 "F.SilkS" user "Ref Des/Silkscreen Top")
		(7 "B.SilkS" user "Ref Des/Silkscreen Bottom")
		(1 "F.Mask" user "Board Geometry/Soldermask Top")
		(3 "B.Mask" user "Board Geometry/Soldermask Bottom")
		(17 "Dwgs.User" user "User.Drawings")
		(19 "Cmts.User" user "User.Comments")
		(21 "Eco1.User" user "User.Eco1")
		(23 "Eco2.User" user "User.Eco2")
		(25 "Edge.Cuts" user "Board Geometry/Outline")
		(27 "Margin" user)
		(31 "F.CrtYd" user "Package Geometry/Place Bound Top")
		(29 "B.CrtYd" user "Package Geometry/Place Bound Bottom")
		(35 "F.Fab" user "Ref Des/Assembly Top")
		(33 "B.Fab" user "Ref Des/Assembly Bottom")
	)
	(footprint ""
		(layer "F.Cu")
		(at 124.714 -127.889)
		(property "Reference" "PC23"
			(at 0 0 0)
			(layer "F.SilkS")
			(hide yes)
			(effects
				(font
					(size 1.27 1.27)
				)
			)
		)
		(property "Value" ""
			(at 0 0 0)
			(layer "F.Fab")
			(effects
				(font
					(size 1.27 1.27)
				)
			)
		)
		(duplicate_pad_numbers_are_jumpers no)
		(fp_line
			(start -2.2098 -0.9398)
			(end 2.2098 -0.9398)
			(stroke
				(width 0.1524)
				(type default)
			)
			(layer "F.SilkS")
		)
		(fp_line
			(start -2.2098 0.9398)
			(end -2.2098 -0.9398)
			(stroke
				(width 0.1524)
				(type default)
			)
			(layer "F.SilkS")
		)
		(fp_line
			(start 2.2098 -0.9398)
			(end 2.2098 0.9398)
			(stroke
				(width 0.1524)
				(type default)
			)
			(layer "F.SilkS")
		)
		(fp_line
			(start 2.2098 0.9398)
			(end -2.2098 0.9398)
			(stroke
				(width 0.1524)
				(type default)
			)
			(layer "F.SilkS")
		)
		(fp_line
			(start -1.700022 -0.899922)
			(end 1.700022 -0.899922)
			(stroke
				(width 0.1)
				(type default)
			)
			(layer "F.Fab")
		)
		(fp_line
			(start -1.700022 0.899922)
			(end -1.700022 -0.899922)
			(stroke
				(width 0.1)
				(type default)
			)
			(layer "F.Fab")
		)
		(fp_line
			(start 1.700022 -0.899922)
			(end 1.700022 0.899922)
			(stroke
				(width 0.1)
				(type default)
			)
			(layer "F.Fab")
		)
		(fp_line
			(start 1.700022 0.899922)
			(end -1.700022 0.899922)
			(stroke
				(width 0.1)
				(type default)
			)
			(layer "F.Fab")
		)
		(pad "1" smd rect
			(at -1.4732 0 180)
			(size 1.1684 1.5748)
			(layers "F.Cu" "F.Mask" "F.Paste")
			(net "P52V_HS_FILTER")
		)
		(pad "2" smd rect
			(at 1.4732 0 180)
			(size 1.1684 1.5748)
			(layers "F.Cu" "F.Mask" "F.Paste")
			(net "GND")
		)
	)
	(footprint ""
		(layer "F.Cu")
		(at 215.646 -95.504 -90)
		(property "Reference" "C23"
			(at 0 0 270)
			(layer "F.SilkS")
			(hide yes)
			(effects
				(font
					(size 1.27 1.27)
				)
			)
		)
		(property "Value" ""
			(at 0 0 270)
			(layer "F.Fab")
			(effects
				(font
					(size 1.27 1.27)
				)
			)
		)
		(duplicate_pad_numbers_are_jumpers no)
		(fp_line
			(start -2.2098 0.9398)
			(end -2.2098 -0.9398)
			(stroke
				(width 0.1524)
				(type default)
			)
			(layer "F.SilkS")
		)
		(fp_line
			(start 2.2098 0.9398)
			(end -2.2098 0.9398)
			(stroke
				(width 0.1524)
				(type default)
			)
			(layer "F.SilkS")
		)
		(fp_line
			(start -2.2098 -0.9398)
			(end 2.2098 -0.9398)
			(stroke
				(width 0.1524)
				(type default)
			)
			(layer "F.SilkS")
		)
		(fp_line
			(start 2.2098 -0.9398)
			(end 2.2098 0.9398)
			(stroke
				(width 0.1524)
				(type default)
			)
			(layer "F.SilkS")
		)
		(fp_line
			(start -1.700022 0.899922)
			(end -1.700022 -0.899922)
			(stroke
				(width 0.1)
				(type default)
			)
			(layer "F.Fab")
		)
		(fp_line
			(start 1.700022 0.899922)
			(end -1.700022 0.899922)
			(stroke
				(width 0.1)
				(type default)
			)
			(layer "F.Fab")
		)
		(fp_line
			(start -1.700022 -0.899922)
			(end 1.700022 -0.899922)
			(stroke
				(width 0.1)
				(type default)
			)
			(layer "F.Fab")
		)
		(fp_line
			(start 1.700022 -0.899922)
			(end 1.700022 0.899922)
			(stroke
				(width 0.1)
				(type default)
			)
			(layer "F.Fab")
		)
		(pad "1" smd rect
			(at -1.4732 0 90)
			(size 1.1684 1.5748)
			(layers "F.Cu" "F.Mask" "F.Paste")
			(net "P52V_HS")
		)
		(pad "2" smd rect
			(at 1.4732 0 90)
			(size 1.1684 1.5748)
			(layers "F.Cu" "F.Mask" "F.Paste")
			(net "GND")
		)
	)
	(footprint ""
		(layer "F.Cu")
		(at 280.39568 -66.152268)
		(property "Reference" "PQ6"
			(at -7.723886 -5.895848 0)
			(unlocked yes)
			(layer "F.SilkS")
			(effects
				(font
					(size 0.7874 0.5842)
					(thickness 0.1524)
				)
				(justify left)
			)
		)
		(property "Value" ""
			(at 0 0 0)
			(layer "F.Fab")
			(effects
				(font
					(size 1.27 1.27)
				)
			)
		)
		(duplicate_pad_numbers_are_jumpers no)
		(fp_line
			(start -7.649972 -4.99999)
			(end -7.649972 -3.3274)
			(stroke
				(width 0.1524)
				(type default)
			)
			(layer "F.SilkS")
		)
		(fp_line
			(start -7.649972 -1.7526)
			(end -7.649972 1.7526)
			(stroke
				(width 0.1524)
				(type default)
			)
			(layer "F.SilkS")
		)
		(fp_line
			(start -7.649972 3.3274)
			(end -7.649972 4.99999)
			(stroke
				(width 0.1524)
				(type default)
			)
			(layer "F.SilkS")
		)
		(fp_line
			(start -7.649972 4.99999)
			(end 5.115814 4.99999)
			(stroke
				(width 0.1524)
				(type default)
			)
			(layer "F.SilkS")
		)
		(fp_line
			(start 5.115814 -4.99999)
			(end -7.649972 -4.99999)
			(stroke
				(width 0.1524)
				(type default)
			)
			(layer "F.SilkS")
		)
		(fp_line
			(start 7.630414 4.99999)
			(end 7.649972 4.99999)
			(stroke
				(width 0.1524)
				(type default)
			)
			(layer "F.SilkS")
		)
		(fp_line
			(start 7.649972 -4.99999)
			(end 7.630414 -4.99999)
			(stroke
				(width 0.1524)
				(type default)
			)
			(layer "F.SilkS")
		)
		(fp_line
			(start 7.649972 4.99999)
			(end 7.649972 -4.99999)
			(stroke
				(width 0.1524)
				(type default)
			)
			(layer "F.SilkS")
		)
		(fp_line
			(start -7.649972 -4.99999)
			(end -7.649972 4.99999)
			(stroke
				(width 0.1)
				(type default)
			)
			(layer "F.Fab")
		)
		(fp_line
			(start -7.649972 4.99999)
			(end 7.649972 4.99999)
			(stroke
				(width 0.1)
				(type default)
			)
			(layer "F.Fab")
		)
		(fp_line
			(start 7.649972 -4.99999)
			(end -7.649972 -4.99999)
			(stroke
				(width 0.1)
				(type default)
			)
			(layer "F.Fab")
		)
		(fp_line
			(start 7.649972 4.99999)
			(end 7.649972 -4.99999)
			(stroke
				(width 0.1)
				(type default)
			)
			(layer "F.Fab")
		)
		(pad "D" smd circle
			(at 2.15011 0)
			(size 0 0)
			(layers "F.Cu" "F.Mask" "F.Paste")
			(net "P52V_HS1_DRAIN_2")
		)
		(pad "G" smd rect
			(at -7.050024 -2.54 270)
			(size 1.3208 3.0988)
			(layers "F.Cu" "F.Mask" "F.Paste")
			(net "P52V_HS1_GATE6")
		)
		(pad "S" smd rect
			(at -7.050024 2.54 270)
			(size 1.3208 3.0988)
			(layers "F.Cu" "F.Mask" "F.Paste")
			(net "P52V_HS")
		)
		(zone
			(layer "F.Cu")
			(hatch none 0.5)
			(connect_pads
				(clearance 0)
			)
			(min_thickness 0.25)
			(keepout
				(tracks not_allowed)
				(vias allowed)
				(pads allowed)
				(copperpour not_allowed)
				(footprints allowed)
			)
			(placement
				(enabled no)
				(sheetname "")
			)
			(fill
				(thermal_gap 0.5)
				(thermal_bridge_width 0.5)
				(island_removal_mode 0)
			)
			(polygon
				(pts
					(xy 285.57728 -71.130668) (xy 272.75028 -71.130668) (xy 272.75028 -69.403468) (xy 274.96008 -69.403468)
					(xy 274.96008 -67.981068) (xy 272.75028 -67.981068) (xy 272.75028 -64.323468) (xy 274.96008 -64.323468)
					(xy 274.96008 -62.901068) (xy 272.75028 -62.901068) (xy 272.75028 -61.173868) (xy 285.57728 -61.173868)
					(xy 285.57728 -62.342268) (xy 279.37968 -62.342268) (xy 279.37968 -69.962268) (xy 285.57728 -69.962268)
				)
			)
		)
	)
	(footprint ""
		(layer "F.Cu")
		(at 276.352 -26.162)
		(property "Reference" "PR6973"
			(at 0 0 0)
			(layer "F.SilkS")
			(hide yes)
			(effects
				(font
					(size 1.27 1.27)
				)
			)
		)
		(property "Value" ""
			(at 0 0 0)
			(layer "F.Fab")
			(effects
				(font
					(size 1.27 1.27)
				)
			)
		)
		(duplicate_pad_numbers_are_jumpers no)
		(fp_line
			(start -0.7874 -0.4064)
			(end 0.7874 -0.4064)
			(stroke
				(width 0.1524)
				(type default)
			)
			(layer "F.SilkS")
		)
		(fp_line
			(start -0.7874 0.4064)
			(end -0.7874 -0.4064)
			(stroke
				(width 0.1524)
				(type default)
			)
			(layer "F.SilkS")
		)
		(fp_line
			(start 0.7874 -0.4064)
			(end 0.7874 0.4064)
			(stroke
				(width 0.1524)
				(type default)
			)
			(layer "F.SilkS")
		)
		(fp_line
			(start 0.7874 0.4064)
			(end -0.7874 0.4064)
			(stroke
				(width 0.1524)
				(type default)
			)
			(layer "F.SilkS")
		)
		(fp_line
			(start -0.67945 -0.305054)
			(end -0.12065 -0.305054)
			(stroke
				(width 0.1)
				(type default)
			)
			(layer "F.Fab")
		)
		(fp_line
			(start -0.67945 0.3048)
			(end -0.67945 -0.305054)
			(stroke
				(width 0.1)
				(type default)
			)
			(layer "F.Fab")
		)
		(fp_line
			(start -0.12065 -0.305054)
			(end -0.12065 -0.2794)
			(stroke
				(width 0.1)
				(type default)
			)
			(layer "F.Fab")
		)
		(fp_line
			(start -0.12065 -0.2794)
			(end 0.12065 -0.2794)
			(stroke
				(width 0.1)
				(type default)
			)
			(layer "F.Fab")
		)
		(fp_line
			(start -0.12065 0.2794)
			(end -0.12065 0.3048)
			(stroke
				(width 0.1)
				(type default)
			)
			(layer "F.Fab")
		)
		(fp_line
			(start -0.12065 0.3048)
			(end -0.67945 0.3048)
			(stroke
				(width 0.1)
				(type default)
			)
			(layer "F.Fab")
		)
		(fp_line
			(start 0.120396 0.2794)
			(end -0.12065 0.2794)
			(stroke
				(width 0.1)
				(type default)
			)
			(layer "F.Fab")
		)
		(fp_line
			(start 0.120396 0.3048)
			(end 0.120396 0.2794)
			(stroke
				(width 0.1)
				(type default)
			)
			(layer "F.Fab")
		)
		(fp_line
			(start 0.12065 -0.3048)
			(end 0.67945 -0.3048)
			(stroke
				(width 0.1)
				(type default)
			)
			(layer "F.Fab")
		)
		(fp_line
			(start 0.12065 -0.2794)
			(end 0.12065 -0.3048)
			(stroke
				(width 0.1)
				(type default)
			)
			(layer "F.Fab")
		)
		(fp_line
			(start 0.67945 -0.3048)
			(end 0.67945 0.3048)
			(stroke
				(width 0.1)
				(type default)
			)
			(layer "F.Fab")
		)
		(fp_line
			(start 0.67945 0.3048)
			(end 0.120396 0.3048)
			(stroke
				(width 0.1)
				(type default)
			)
			(layer "F.Fab")
		)
		(pad "1" smd circle
			(at -0.40005 0)
			(size 0 0)
			(layers "F.Cu" "F.Mask" "F.Paste")
			(net "P52V_HS1_EN")
		)
		(pad "2" smd circle
			(at 0.40005 0)
			(size 0 0)
			(layers "F.Cu" "F.Mask" "F.Paste")
			(net "P52V_HS1_R_EN")
		)
	)
	(footprint ""
		(layer "F.Cu")
		(at 299.593 -124.2695 180)
		(property "Reference" "PR6972"
			(at 0 0 180)
			(layer "F.SilkS")
			(hide yes)
			(effects
				(font
					(size 1.27 1.27)
				)
			)
		)
		(property "Value" ""
			(at 0 0 180)
			(layer "F.Fab")
			(effects
				(font
					(size 1.27 1.27)
				)
			)
		)
		(duplicate_pad_numbers_are_jumpers no)
		(fp_line
			(start 0.7874 0.4064)
			(end -0.7874 0.4064)
			(stroke
				(width 0.1524)
				(type default)
			)
			(layer "F.SilkS")
		)
		(fp_line
			(start 0.7874 -0.4064)
			(end 0.7874 0.4064)
			(stroke
				(width 0.1524)
				(type default)
			)
			(layer "F.SilkS")
		)
		(fp_line
			(start -0.7874 0.4064)
			(end -0.7874 -0.4064)
			(stroke
				(width 0.1524)
				(type default)
			)
			(layer "F.SilkS")
		)
		(fp_line
			(start -0.7874 -0.4064)
			(end 0.7874 -0.4064)
			(stroke
				(width 0.1524)
				(type default)
			)
			(layer "F.SilkS")
		)
		(fp_line
			(start 0.67945 0.3048)
			(end 0.120396 0.3048)
			(stroke
				(width 0.1)
				(type default)
			)
			(layer "F.Fab")
		)
		(fp_line
			(start 0.67945 -0.3048)
			(end 0.67945 0.3048)
			(stroke
				(width 0.1)
				(type default)
			)
			(layer "F.Fab")
		)
		(fp_line
			(start 0.12065 -0.2794)
			(end 0.12065 -0.3048)
			(stroke
				(width 0.1)
				(type default)
			)
			(layer "F.Fab")
		)
		(fp_line
			(start 0.12065 -0.3048)
			(end 0.67945 -0.3048)
			(stroke
				(width 0.1)
				(type default)
			)
			(layer "F.Fab")
		)
		(fp_line
			(start 0.120396 0.3048)
			(end 0.120396 0.2794)
			(stroke
				(width 0.1)
				(type default)
			)
			(layer "F.Fab")
		)
		(fp_line
			(start 0.120396 0.2794)
			(end -0.12065 0.2794)
			(stroke
				(width 0.1)
				(type default)
			)
			(layer "F.Fab")
		)
		(fp_line
			(start -0.12065 0.3048)
			(end -0.67945 0.3048)
			(stroke
				(width 0.1)
				(type default)
			)
			(layer "F.Fab")
		)
		(fp_line
			(start -0.12065 0.2794)
			(end -0.12065 0.3048)
			(stroke
				(width 0.1)
				(type default)
			)
			(layer "F.Fab")
		)
		(fp_line
			(start -0.12065 -0.2794)
			(end 0.12065 -0.2794)
			(stroke
				(width 0.1)
				(type default)
			)
			(layer "F.Fab")
		)
		(fp_line
			(start -0.12065 -0.305054)
			(end -0.12065 -0.2794)
			(stroke
				(width 0.1)
				(type default)
			)
			(layer "F.Fab")
		)
		(fp_line
			(start -0.67945 0.3048)
			(end -0.67945 -0.305054)
			(stroke
				(width 0.1)
				(type default)
			)
			(layer "F.Fab")
		)
		(fp_line
			(start -0.67945 -0.305054)
			(end -0.12065 -0.305054)
			(stroke
				(width 0.1)
				(type default)
			)
			(layer "F.Fab")
		)
		(pad "1" smd circle
			(at -0.40005 0 180)
			(size 0 0)
			(layers "F.Cu" "F.Mask" "F.Paste")
			(net "P52V_HS_4287_S1P")
		)
		(pad "2" smd circle
			(at 0.40005 0 180)
			(size 0 0)
			(layers "F.Cu" "F.Mask" "F.Paste")
			(net "P52V_HS_4287_S1N")
		)
	)
	(footprint ""
		(layer "F.Cu")
		(at 191.643 -8.763)
		(property "Reference" "PC105"
			(at 0 0 0)
			(layer "F.SilkS")
			(hide yes)
			(effects
				(font
					(size 1.27 1.27)
				)
			)
		)
		(property "Value" ""
			(at 0 0 0)
			(layer "F.Fab")
			(effects
				(font
					(size 1.27 1.27)
				)
			)
		)
		(duplicate_pad_numbers_are_jumpers no)
		(fp_line
			(start -1.524 -0.762)
			(end 1.524 -0.762)
			(stroke
				(width 0.1524)
				(type default)
			)
			(layer "F.SilkS")
		)
		(fp_line
			(start -1.524 0.762)
			(end -1.524 -0.762)
			(stroke
				(width 0.1524)
				(type default)
			)
			(layer "F.SilkS")
		)
		(fp_line
			(start 1.524 -0.762)
			(end 1.524 0.762)
			(stroke
				(width 0.1524)
				(type default)
			)
			(layer "F.SilkS")
		)
		(fp_line
			(start 1.524 0.762)
			(end -1.524 0.762)
			(stroke
				(width 0.1524)
				(type default)
			)
			(layer "F.SilkS")
		)
		(fp_line
			(start -1.1049 -0.724916)
			(end -1.1049 0.724916)
			(stroke
				(width 0.1)
				(type default)
			)
			(layer "F.Fab")
		)
		(fp_line
			(start -1.1049 0.724916)
			(end 1.1049 0.724916)
			(stroke
				(width 0.1)
				(type default)
			)
			(layer "F.Fab")
		)
		(fp_line
			(start 1.1049 -0.724916)
			(end -1.1049 -0.724916)
			(stroke
				(width 0.1)
				(type default)
			)
			(layer "F.Fab")
		)
		(fp_line
			(start 1.1049 0.724916)
			(end 1.1049 -0.724916)
			(stroke
				(width 0.1)
				(type default)
			)
			(layer "F.Fab")
		)
		(pad "1" smd rect
			(at -0.889 0 180)
			(size 1.016 1.27)
			(layers "F.Cu" "F.Mask" "F.Paste")
			(net "P3V3_AUX")
		)
		(pad "2" smd rect
			(at 0.889 0 180)
			(size 1.016 1.27)
			(layers "F.Cu" "F.Mask" "F.Paste")
			(net "GND")
		)
	)
)
